# S9S_MB_2U (Grand Teton) — schematic netlist excerpt (pin names and nets, part order shuffled) for the footprints in the layout excerpt that follows; sources: Cadence DE-HDL packaged netlist, KiCad conversion of 03242023_DA0F0TMBIJ0_F0T_Motherboard_J_brd_V01_OCP.brd

U23  74LVC1G02GW  IC  pkg SMLF  page 133
  B  = FM_CPU1_SKTOCC_N
  A  = FM_CPU0_SKTOCC_N
  GND  = GND
  Y  = FM_CPU_EN
  VCC  = P3V3_AUX

R3771  Q_RES  10K 1% CHIP  pkg 0402LF  page 191 : A = P3V3_AUX ; B = E1S_0_PWRDIS
C326  Q_CAP  47UF 4V 20% X6S  pkg C0805  page 78 : A = PVCCIN_CPU1 ; B = GND

(kicad_pcb
	(version 20260206)
	(generator "pcbnew")
	(generator_version "10.0")
	(general
		(thickness 1.6)
		(legacy_teardrops no)
	)
	(paper "A4")
	(title_block
		(title "03242023_DA0F0TMBIJ0_F0T_Motherboard_J_brd_V01_OCP.brd")
		(comment 1 "Grand Teton / footprints 5388-5390 of 6105")
	)
	(layers
		(0 "F.Cu" signal "TOP")
		(4 "In1.Cu" signal "GND")
		(6 "In2.Cu" signal "IN1")
		(8 "In3.Cu" signal "GND1")
		(10 "In4.Cu" signal "IN2")
		(12 "In5.Cu" signal "GND2")
		(14 "In6.Cu" signal "IN3")
		(16 "In7.Cu" signal "GND3")
		(18 "In8.Cu" signal "VCC")
		(20 "In9.Cu" signal "VCC1")
		(22 "In10.Cu" signal "GND4")
		(24 "In11.Cu" signal "IN4")
		(26 "In12.Cu" signal "GND5")
		(28 "In13.Cu" signal "IN5")
		(30 "In14.Cu" signal "GND6")
		(32 "In15.Cu" signal "IN6")
		(34 "In16.Cu" signal "GND7")
		(2 "B.Cu" signal "BOTTOM")
		(9 "F.Adhes" user "F.Adhesive")
		(11 "B.Adhes" user "B.Adhesive")
		(13 "F.Paste" user "Package Geometry/Pastemask Top")
		(15 "B.Paste" user "Package Geometry/Pastemask Bottom")
		(5 "F.SilkS" user "Ref Des/Silkscreen Top")
		(7 "B.SilkS" user "Ref Des/Silkscreen Bottom")
		(1 "F.Mask" user "Board Geometry/Soldermask Top")
		(3 "B.Mask" user "Board Geometry/Soldermask Bottom")
		(17 "Dwgs.User" user "User.Drawings")
		(19 "Cmts.User" user "User.Comments")
		(21 "Eco1.User" user "User.Eco1")
		(23 "Eco2.User" user "User.Eco2")
		(25 "Edge.Cuts" user "Board Geometry/Outline")
		(27 "Margin" user)
		(31 "F.CrtYd" user "Package Geometry/Place Bound Top")
		(29 "B.CrtYd" user "Package Geometry/Place Bound Bottom")
		(35 "F.Fab" user "Ref Des/Assembly Top")
		(33 "B.Fab" user "Ref Des/Assembly Bottom")
	)
	(footprint ""
		(layer "B.Cu")
		(at 116.40312 -237.718092 90)
		(property "Reference" "C326"
			(at 0 0 90)
			(layer "B.SilkS")
			(hide yes)
			(effects
				(font
					(size 1.27 1.27)
				)
				(justify mirror)
			)
		)
		(property "Value" ""
			(at 0 0 90)
			(layer "B.Fab")
			(effects
				(font
					(size 1.27 1.27)
				)
				(justify mirror)
			)
		)
		(duplicate_pad_numbers_are_jumpers no)
		(fp_line
			(start 1.524 -0.762)
			(end -1.524 -0.762)
			(stroke
				(width 0.1524)
				(type default)
			)
			(layer "B.SilkS")
		)
		(fp_line
			(start -1.524 -0.762)
			(end -1.524 0.762)
			(stroke
				(width 0.1524)
				(type default)
			)
			(layer "B.SilkS")
		)
		(fp_line
			(start 1.524 0.762)
			(end 1.524 -0.762)
			(stroke
				(width 0.1524)
				(type default)
			)
			(layer "B.SilkS")
		)
		(fp_line
			(start -1.524 0.762)
			(end 1.524 0.762)
			(stroke
				(width 0.1524)
				(type default)
			)
			(layer "B.SilkS")
		)
		(fp_line
			(start 1.1049 -0.724916)
			(end 1.1049 0.724916)
			(stroke
				(width 0.1)
				(type default)
			)
			(layer "B.Fab")
		)
		(fp_line
			(start -1.1049 -0.724916)
			(end 1.1049 -0.724916)
			(stroke
				(width 0.1)
				(type default)
			)
			(layer "B.Fab")
		)
		(fp_line
			(start 1.1049 0.724916)
			(end -1.1049 0.724916)
			(stroke
				(width 0.1)
				(type default)
			)
			(layer "B.Fab")
		)
		(fp_line
			(start -1.1049 0.724916)
			(end -1.1049 -0.724916)
			(stroke
				(width 0.1)
				(type default)
			)
			(layer "B.Fab")
		)
		(pad "1" smd rect
			(at 0.889 0 90)
			(size 1.016 1.27)
			(layers "B.Cu" "B.Mask" "B.Paste")
			(net "PVCCIN_CPU1")
		)
		(pad "2" smd rect
			(at -0.889 0 90)
			(size 1.016 1.27)
			(layers "B.Cu" "B.Mask" "B.Paste")
			(net "GND")
		)
	)
	(footprint ""
		(layer "B.Cu")
		(at 236.20095 -50.193448 180)
		(property "Reference" "R3771"
			(at 0 0 0)
			(layer "B.SilkS")
			(hide yes)
			(effects
				(font
					(size 1.27 1.27)
				)
				(justify mirror)
			)
		)
		(property "Value" ""
			(at 0 0 0)
			(layer "B.Fab")
			(effects
				(font
					(size 1.27 1.27)
				)
				(justify mirror)
			)
		)
		(duplicate_pad_numbers_are_jumpers no)
		(fp_line
			(start 0.7874 0.4064)
			(end 0.7874 -0.4064)
			(stroke
				(width 0.1524)
				(type default)
			)
			(layer "B.SilkS")
		)
		(fp_line
			(start 0.7874 -0.4064)
			(end -0.7874 -0.4064)
			(stroke
				(width 0.1524)
				(type default)
			)
			(layer "B.SilkS")
		)
		(fp_line
			(start -0.7874 0.4064)
			(end 0.7874 0.4064)
			(stroke
				(width 0.1524)
				(type default)
			)
			(layer "B.SilkS")
		)
		(fp_line
			(start -0.7874 -0.4064)
			(end -0.7874 0.4064)
			(stroke
				(width 0.1524)
				(type default)
			)
			(layer "B.SilkS")
		)
		(fp_line
			(start 0.67945 0.3048)
			(end 0.67945 -0.305054)
			(stroke
				(width 0.1)
				(type default)
			)
			(layer "B.Fab")
		)
		(fp_line
			(start 0.67945 -0.305054)
			(end 0.12065 -0.305054)
			(stroke
				(width 0.1)
				(type default)
			)
			(layer "B.Fab")
		)
		(fp_line
			(start 0.12065 0.3048)
			(end 0.67945 0.3048)
			(stroke
				(width 0.1)
				(type default)
			)
			(layer "B.Fab")
		)
		(fp_line
			(start 0.12065 0.2794)
			(end 0.12065 0.3048)
			(stroke
				(width 0.1)
				(type default)
			)
			(layer "B.Fab")
		)
		(fp_line
			(start 0.12065 -0.2794)
			(end -0.12065 -0.2794)
			(stroke
				(width 0.1)
				(type default)
			)
			(layer "B.Fab")
		)
		(fp_line
			(start 0.12065 -0.305054)
			(end 0.12065 -0.2794)
			(stroke
				(width 0.1)
				(type default)
			)
			(layer "B.Fab")
		)
		(fp_line
			(start -0.120396 0.3048)
			(end -0.120396 0.2794)
			(stroke
				(width 0.1)
				(type default)
			)
			(layer "B.Fab")
		)
		(fp_line
			(start -0.120396 0.2794)
			(end 0.12065 0.2794)
			(stroke
				(width 0.1)
				(type default)
			)
			(layer "B.Fab")
		)
		(fp_line
			(start -0.12065 -0.2794)
			(end -0.12065 -0.3048)
			(stroke
				(width 0.1)
				(type default)
			)
			(layer "B.Fab")
		)
		(fp_line
			(start -0.12065 -0.3048)
			(end -0.67945 -0.3048)
			(stroke
				(width 0.1)
				(type default)
			)
			(layer "B.Fab")
		)
		(fp_line
			(start -0.67945 0.3048)
			(end -0.120396 0.3048)
			(stroke
				(width 0.1)
				(type default)
			)
			(layer "B.Fab")
		)
		(fp_line
			(start -0.67945 -0.3048)
			(end -0.67945 0.3048)
			(stroke
				(width 0.1)
				(type default)
			)
			(layer "B.Fab")
		)
		(pad "1" smd circle
			(at 0.40005 0)
			(size 0 0)
			(layers "B.Cu" "B.Mask" "B.Paste")
			(net "P3V3_AUX")
		)
		(pad "2" smd circle
			(at -0.40005 0)
			(size 0 0)
			(layers "B.Cu" "B.Mask" "B.Paste")
			(net "E1S_0_PWRDIS")
		)
	)
	(footprint ""
		(layer "B.Cu")
		(at 196.906896 -193.267584)
		(property "Reference" "U23"
			(at 1.524 -1.87833 0)
			(unlocked yes)
			(layer "B.SilkS")
			(effects
				(font
					(size 0.7874 0.5842)
					(thickness 0.1524)
				)
				(justify left mirror)
			)
		)
		(property "Value" ""
			(at 0 0 0)
			(layer "B.Fab")
			(effects
				(font
					(size 1.27 1.27)
				)
				(justify mirror)
			)
		)
		(duplicate_pad_numbers_are_jumpers no)
		(fp_line
			(start -1.4986 -1.100074)
			(end -1.4986 1.100074)
			(stroke
				(width 0.1524)
				(type default)
			)
			(layer "B.SilkS")
		)
		(fp_line
			(start -1.4986 1.100074)
			(end 1.4986 1.100074)
			(stroke
				(width 0.1524)
				(type default)
			)
			(layer "B.SilkS")
		)
		(fp_line
			(start 1.4986 -1.100074)
			(end -1.4986 -1.100074)
			(stroke
				(width 0.1524)
				(type default)
			)
			(layer "B.SilkS")
		)
		(fp_line
			(start 1.4986 1.100074)
			(end 1.4986 -1.100074)
			(stroke
				(width 0.1524)
				(type default)
			)
			(layer "B.SilkS")
		)
		(fp_poly
			(pts
				(xy 2.15138 -0.417068) (xy 1.59766 -0.71374) (xy 2.15138 -1.041908)
			)
			(stroke
				(width 0)
				(type default)
			)
			(fill yes)
			(layer "B.SilkS")
		)
		(fp_line
			(start -0.67437 -1.100074)
			(end -0.67437 1.100074)
			(stroke
				(width 0.1)
				(type default)
			)
			(layer "B.Fab")
		)
		(fp_line
			(start -0.67437 1.100074)
			(end 0.67437 1.100074)
			(stroke
				(width 0.1)
				(type default)
			)
			(layer "B.Fab")
		)
		(fp_line
			(start 0.67437 -1.100074)
			(end -0.67437 -1.100074)
			(stroke
				(width 0.1)
				(type default)
			)
			(layer "B.Fab")
		)
		(fp_line
			(start 0.67437 1.100074)
			(end 0.67437 -1.100074)
			(stroke
				(width 0.1)
				(type default)
			)
			(layer "B.Fab")
		)
		(fp_poly
			(pts
				(xy 2.20472 -0.338328) (xy 2.20472 -0.963168) (xy 1.651 -0.635)
			)
			(stroke
				(width 0)
				(type default)
			)
			(fill yes)
			(layer "B.Fab")
		)
		(pad "1" smd rect
			(at 0.889 -0.649986 180)
			(size 1.016 0.381)
			(layers "B.Cu" "B.Mask" "B.Paste")
			(net "FM_CPU1_SKTOCC_N")
		)
		(pad "2" smd rect
			(at 0.889 0 180)
			(size 1.016 0.381)
			(layers "B.Cu" "B.Mask" "B.Paste")
			(net "FM_CPU0_SKTOCC_N")
		)
		(pad "3" smd rect
			(at 0.889 0.649986 180)
			(size 1.016 0.381)
			(layers "B.Cu" "B.Mask" "B.Paste")
			(net "GND")
		)
		(pad "4" smd rect
			(at -0.889 0.649986 180)
			(size 1.016 0.381)
			(layers "B.Cu" "B.Mask" "B.Paste")
			(net "FM_CPU_EN")
		)
		(pad "5" smd rect
			(at -0.889 -0.649986 180)
			(size 1.016 0.381)
			(layers "B.Cu" "B.Mask" "B.Paste")
			(net "P3V3_AUX")
		)
	)
)
